(kicad_pcb
	(version 20260206)
	(generator "pcbnew")
	(generator_version "10.0")
	(general
		(thickness 1.6)
		(legacy_teardrops no)
	)
	(paper "A4")
	(title_block
		(title "04192023_DAF0TMB3IC0_F0TG_MB_C_brd_V02_OCP.brd")
		(comment 1 "Grand Teton / footprints 3976-3983 of 8354")
	)
	(layers
		(0 "F.Cu" signal "TOP")
		(4 "In1.Cu" signal "GND")
		(6 "In2.Cu" signal "IN1")
		(8 "In3.Cu" signal "GND1")
		(10 "In4.Cu" signal "IN2")
		(12 "In5.Cu" signal "GND2")
		(14 "In6.Cu" signal "IN3")
		(16 "In7.Cu" signal "GND3")
		(18 "In8.Cu" signal "VCC")
		(20 "In9.Cu" signal "VCC1")
		(22 "In10.Cu" signal "GND4")
		(24 "In11.Cu" signal "IN4")
		(26 "In12.Cu" signal "GND5")
		(28 "In13.Cu" signal "IN5")
		(30 "In14.Cu" signal "GND6")
		(32 "In15.Cu" signal "IN6")
		(34 "In16.Cu" signal "GND7")
		(2 "B.Cu" signal "BOTTOM")
		(9 "F.Adhes" user "F.Adhesive")
		(11 "B.Adhes" user "B.Adhesive")
		(13 "F.Paste" user "Package Geometry/Pastemask Top")
		(15 "B.Paste" user "Package Geometry/Pastemask Bottom")
		(5 "F.SilkS" user "Ref Des/Silkscreen Top")
		(7 "B.SilkS" user "Ref Des/Silkscreen Bottom")
		(1 "F.Mask" user "Board Geometry/Soldermask Top")
		(3 "B.Mask" user "Board Geometry/Soldermask Bottom")
		(17 "Dwgs.User" user "User.Drawings")
		(19 "Cmts.User" user "User.Comments")
		(21 "Eco1.User" user "User.Eco1")
		(23 "Eco2.User" user "User.Eco2")
		(25 "Edge.Cuts" user "Board Geometry/Outline")
		(27 "Margin" user)
		(31 "F.CrtYd" user "Package Geometry/Place Bound Top")
		(29 "B.CrtYd" user "Package Geometry/Place Bound Bottom")
		(35 "F.Fab" user "Ref Des/Assembly Top")
		(33 "B.Fab" user "Ref Des/Assembly Bottom")
	)
	(footprint ""
		(layer "F.Cu")
		(at 352.298 -407.8732 90)
		(property "Reference" "R1471"
			(at 0 0 90)
			(layer "F.SilkS")
			(hide yes)
			(effects
				(font
					(size 1.27 1.27)
				)
			)
		)
		(property "Value" ""
			(at 0 0 90)
			(layer "F.Fab")
			(effects
				(font
					(size 1.27 1.27)
				)
			)
		)
		(duplicate_pad_numbers_are_jumpers no)
		(fp_line
			(start 0.32512 -0.175006)
			(end 0.32512 0.175006)
			(stroke
				(width 0.1)
				(type default)
			)
			(layer "F.Fab")
		)
		(fp_line
			(start -0.32512 -0.175006)
			(end 0.32512 -0.175006)
			(stroke
				(width 0.1)
				(type default)
			)
			(layer "F.Fab")
		)
		(fp_line
			(start 0.32512 0.175006)
			(end -0.32512 0.175006)
			(stroke
				(width 0.1)
				(type default)
			)
			(layer "F.Fab")
		)
		(fp_line
			(start -0.32512 0.175006)
			(end -0.32512 -0.175006)
			(stroke
				(width 0.1)
				(type default)
			)
			(layer "F.Fab")
		)
		(pad "1" smd rect
			(at -0.2667 0 90)
			(size 0.3048 0.381)
			(layers "F.Cu" "F.Mask" "F.Paste")
			(net "P1V8_CPU0_RT_1D")
		)
		(pad "2" smd rect
			(at 0.2667 0 270)
			(size 0.3048 0.381)
			(layers "F.Cu" "F.Mask" "F.Paste")
			(net "JTAG_TMS_RT_CPU0_P1")
		)
	)
	(footprint ""
		(layer "F.Cu")
		(at 348.052136 -147.904962)
		(property "Reference" "H54"
			(at -3.9116 -3.83413 0)
			(unlocked yes)
			(layer "F.SilkS")
			(effects
				(font
					(size 0.7874 0.5842)
					(thickness 0.1524)
				)
				(justify left)
			)
		)
		(property "Value" ""
			(at 0 0 0)
			(layer "F.Fab")
			(effects
				(font
					(size 1.27 1.27)
				)
			)
		)
		(duplicate_pad_numbers_are_jumpers no)
		(pad "1" thru_hole circle
			(at 0 0)
			(size 6.1976 6.1976)
			(drill 3.7338)
			(layers "*.Cu" "*.Mask")
			(remove_unused_layers no)
			(net "GND")
			(clearance -0.9779)
			(padstack
				(mode front_inner_back)
				(layer "Inner"
					(shape circle)
					(size 5.5372 5.5372)
					(clearance -0.6477)
				)
				(layer "B.Cu"
					(shape circle)
					(size 6.1976 6.1976)
					(clearance -0.9779)
				)
			)
		)
	)
	(footprint ""
		(layer "F.Cu")
		(at 213.889844 -125.643894)
		(property "Reference" "R899"
			(at 0 0 0)
			(layer "F.SilkS")
			(hide yes)
			(effects
				(font
					(size 1.27 1.27)
				)
			)
		)
		(property "Value" ""
			(at 0 0 0)
			(layer "F.Fab")
			(effects
				(font
					(size 1.27 1.27)
				)
			)
		)
		(duplicate_pad_numbers_are_jumpers no)
		(fp_line
			(start -0.7874 -0.4064)
			(end 0.7874 -0.4064)
			(stroke
				(width 0.1524)
				(type default)
			)
			(layer "F.SilkS")
		)
		(fp_line
			(start -0.7874 0.4064)
			(end -0.7874 -0.4064)
			(stroke
				(width 0.1524)
				(type default)
			)
			(layer "F.SilkS")
		)
		(fp_line
			(start 0.7874 -0.4064)
			(end 0.7874 0.4064)
			(stroke
				(width 0.1524)
				(type default)
			)
			(layer "F.SilkS")
		)
		(fp_line
			(start 0.7874 0.4064)
			(end -0.7874 0.4064)
			(stroke
				(width 0.1524)
				(type default)
			)
			(layer "F.SilkS")
		)
		(fp_line
			(start -0.67945 -0.305054)
			(end -0.12065 -0.305054)
			(stroke
				(width 0.1)
				(type default)
			)
			(layer "F.Fab")
		)
		(fp_line
			(start -0.67945 0.3048)
			(end -0.67945 -0.305054)
			(stroke
				(width 0.1)
				(type default)
			)
			(layer "F.Fab")
		)
		(fp_line
			(start -0.12065 -0.305054)
			(end -0.12065 -0.2794)
			(stroke
				(width 0.1)
				(type default)
			)
			(layer "F.Fab")
		)
		(fp_line
			(start -0.12065 -0.2794)
			(end 0.12065 -0.2794)
			(stroke
				(width 0.1)
				(type default)
			)
			(layer "F.Fab")
		)
		(fp_line
			(start -0.12065 0.2794)
			(end -0.12065 0.3048)
			(stroke
				(width 0.1)
				(type default)
			)
			(layer "F.Fab")
		)
		(fp_line
			(start -0.12065 0.3048)
			(end -0.67945 0.3048)
			(stroke
				(width 0.1)
				(type default)
			)
			(layer "F.Fab")
		)
		(fp_line
			(start 0.120396 0.2794)
			(end -0.12065 0.2794)
			(stroke
				(width 0.1)
				(type default)
			)
			(layer "F.Fab")
		)
		(fp_line
			(start 0.120396 0.3048)
			(end 0.120396 0.2794)
			(stroke
				(width 0.1)
				(type default)
			)
			(layer "F.Fab")
		)
		(fp_line
			(start 0.12065 -0.3048)
			(end 0.67945 -0.3048)
			(stroke
				(width 0.1)
				(type default)
			)
			(layer "F.Fab")
		)
		(fp_line
			(start 0.12065 -0.2794)
			(end 0.12065 -0.3048)
			(stroke
				(width 0.1)
				(type default)
			)
			(layer "F.Fab")
		)
		(fp_line
			(start 0.67945 -0.3048)
			(end 0.67945 0.3048)
			(stroke
				(width 0.1)
				(type default)
			)
			(layer "F.Fab")
		)
		(fp_line
			(start 0.67945 0.3048)
			(end 0.120396 0.3048)
			(stroke
				(width 0.1)
				(type default)
			)
			(layer "F.Fab")
		)
		(pad "1" smd circle
			(at -0.40005 0)
			(size 0 0)
			(layers "F.Cu" "F.Mask" "F.Paste")
			(net "RST_PERST_OCP_SFF_BUF2_N")
		)
		(pad "2" smd circle
			(at 0.40005 0)
			(size 0 0)
			(layers "F.Cu" "F.Mask" "F.Paste")
			(net "RST_PERST1_OCP_SFF_N")
		)
	)
	(footprint ""
		(layer "F.Cu")
		(at 184.622694 -410.144722)
		(property "Reference" "R8027"
			(at 0 0 0)
			(layer "F.SilkS")
			(hide yes)
			(effects
				(font
					(size 1.27 1.27)
				)
			)
		)
		(property "Value" ""
			(at 0 0 0)
			(layer "F.Fab")
			(effects
				(font
					(size 1.27 1.27)
				)
			)
		)
		(duplicate_pad_numbers_are_jumpers no)
		(fp_line
			(start -0.7874 -0.4064)
			(end 0.7874 -0.4064)
			(stroke
				(width 0.1524)
				(type default)
			)
			(layer "F.SilkS")
		)
		(fp_line
			(start -0.7874 0.4064)
			(end -0.7874 -0.4064)
			(stroke
				(width 0.1524)
				(type default)
			)
			(layer "F.SilkS")
		)
		(fp_line
			(start 0.7874 -0.4064)
			(end 0.7874 0.4064)
			(stroke
				(width 0.1524)
				(type default)
			)
			(layer "F.SilkS")
		)
		(fp_line
			(start 0.7874 0.4064)
			(end -0.7874 0.4064)
			(stroke
				(width 0.1524)
				(type default)
			)
			(layer "F.SilkS")
		)
		(fp_line
			(start -0.67945 -0.305054)
			(end -0.12065 -0.305054)
			(stroke
				(width 0.1)
				(type default)
			)
			(layer "F.Fab")
		)
		(fp_line
			(start -0.67945 0.3048)
			(end -0.67945 -0.305054)
			(stroke
				(width 0.1)
				(type default)
			)
			(layer "F.Fab")
		)
		(fp_line
			(start -0.12065 -0.305054)
			(end -0.12065 -0.2794)
			(stroke
				(width 0.1)
				(type default)
			)
			(layer "F.Fab")
		)
		(fp_line
			(start -0.12065 -0.2794)
			(end 0.12065 -0.2794)
			(stroke
				(width 0.1)
				(type default)
			)
			(layer "F.Fab")
		)
		(fp_line
			(start -0.12065 0.2794)
			(end -0.12065 0.3048)
			(stroke
				(width 0.1)
				(type default)
			)
			(layer "F.Fab")
		)
		(fp_line
			(start -0.12065 0.3048)
			(end -0.67945 0.3048)
			(stroke
				(width 0.1)
				(type default)
			)
			(layer "F.Fab")
		)
		(fp_line
			(start 0.120396 0.2794)
			(end -0.12065 0.2794)
			(stroke
				(width 0.1)
				(type default)
			)
			(layer "F.Fab")
		)
		(fp_line
			(start 0.120396 0.3048)
			(end 0.120396 0.2794)
			(stroke
				(width 0.1)
				(type default)
			)
			(layer "F.Fab")
		)
		(fp_line
			(start 0.12065 -0.3048)
			(end 0.67945 -0.3048)
			(stroke
				(width 0.1)
				(type default)
			)
			(layer "F.Fab")
		)
		(fp_line
			(start 0.12065 -0.2794)
			(end 0.12065 -0.3048)
			(stroke
				(width 0.1)
				(type default)
			)
			(layer "F.Fab")
		)
		(fp_line
			(start 0.67945 -0.3048)
			(end 0.67945 0.3048)
			(stroke
				(width 0.1)
				(type default)
			)
			(layer "F.Fab")
		)
		(fp_line
			(start 0.67945 0.3048)
			(end 0.120396 0.3048)
			(stroke
				(width 0.1)
				(type default)
			)
			(layer "F.Fab")
		)
		(pad "1" smd circle
			(at -0.40005 0)
			(size 0 0)
			(layers "F.Cu" "F.Mask" "F.Paste")
			(net "LED_P12V_PSU_R3")
		)
		(pad "2" smd circle
			(at 0.40005 0)
			(size 0 0)
			(layers "F.Cu" "F.Mask" "F.Paste")
			(net "P12V_PSU")
		)
	)
	(footprint ""
		(layer "F.Cu")
		(at 314.305696 -378.95403 -90)
		(property "Reference" "C915"
			(at 0 0 270)
			(layer "F.SilkS")
			(hide yes)
			(effects
				(font
					(size 1.27 1.27)
				)
			)
		)
		(property "Value" ""
			(at 0 0 270)
			(layer "F.Fab")
			(effects
				(font
					(size 1.27 1.27)
				)
			)
		)
		(duplicate_pad_numbers_are_jumpers no)
		(fp_line
			(start -0.299974 0.150114)
			(end -0.299974 -0.150114)
			(stroke
				(width 0.1)
				(type default)
			)
			(layer "F.Fab")
		)
		(fp_line
			(start 0.299974 0.150114)
			(end -0.299974 0.150114)
			(stroke
				(width 0.1)
				(type default)
			)
			(layer "F.Fab")
		)
		(fp_line
			(start -0.299974 -0.150114)
			(end 0.299974 -0.150114)
			(stroke
				(width 0.1)
				(type default)
			)
			(layer "F.Fab")
		)
		(fp_line
			(start 0.299974 -0.150114)
			(end 0.299974 0.150114)
			(stroke
				(width 0.1)
				(type default)
			)
			(layer "F.Fab")
		)
		(pad "1" smd rect
			(at -0.2667 0 270)
			(size 0.3048 0.381)
			(layers "F.Cu" "F.Mask" "F.Paste")
			(net "P5E_CPU0_P0_TX_C_DP<9>")
		)
		(pad "2" smd rect
			(at 0.2667 0 270)
			(size 0.3048 0.381)
			(layers "F.Cu" "F.Mask" "F.Paste")
			(net "P5E_CPU0_P0_TX_DP<9>")
		)
	)
	(footprint ""
		(layer "F.Cu")
		(at 180.457856 -139.947142 -90)
		(property "Reference" "R6740"
			(at 0 0 270)
			(layer "F.SilkS")
			(hide yes)
			(effects
				(font
					(size 1.27 1.27)
				)
			)
		)
		(property "Value" ""
			(at 0 0 270)
			(layer "F.Fab")
			(effects
				(font
					(size 1.27 1.27)
				)
			)
		)
		(duplicate_pad_numbers_are_jumpers no)
		(fp_line
			(start -0.7874 0.4064)
			(end -0.7874 -0.4064)
			(stroke
				(width 0.1524)
				(type default)
			)
			(layer "F.SilkS")
		)
		(fp_line
			(start 0.7874 0.4064)
			(end -0.7874 0.4064)
			(stroke
				(width 0.1524)
				(type default)
			)
			(layer "F.SilkS")
		)
		(fp_line
			(start -0.7874 -0.4064)
			(end 0.7874 -0.4064)
			(stroke
				(width 0.1524)
				(type default)
			)
			(layer "F.SilkS")
		)
		(fp_line
			(start 0.7874 -0.4064)
			(end 0.7874 0.4064)
			(stroke
				(width 0.1524)
				(type default)
			)
			(layer "F.SilkS")
		)
		(fp_line
			(start -0.67945 0.3048)
			(end -0.67945 -0.305054)
			(stroke
				(width 0.1)
				(type default)
			)
			(layer "F.Fab")
		)
		(fp_line
			(start -0.12065 0.3048)
			(end -0.67945 0.3048)
			(stroke
				(width 0.1)
				(type default)
			)
			(layer "F.Fab")
		)
		(fp_line
			(start 0.120396 0.3048)
			(end 0.120396 0.2794)
			(stroke
				(width 0.1)
				(type default)
			)
			(layer "F.Fab")
		)
		(fp_line
			(start 0.67945 0.3048)
			(end 0.120396 0.3048)
			(stroke
				(width 0.1)
				(type default)
			)
			(layer "F.Fab")
		)
		(fp_line
			(start -0.12065 0.2794)
			(end -0.12065 0.3048)
			(stroke
				(width 0.1)
				(type default)
			)
			(layer "F.Fab")
		)
		(fp_line
			(start 0.120396 0.2794)
			(end -0.12065 0.2794)
			(stroke
				(width 0.1)
				(type default)
			)
			(layer "F.Fab")
		)
		(fp_line
			(start -0.12065 -0.2794)
			(end 0.12065 -0.2794)
			(stroke
				(width 0.1)
				(type default)
			)
			(layer "F.Fab")
		)
		(fp_line
			(start 0.12065 -0.2794)
			(end 0.12065 -0.3048)
			(stroke
				(width 0.1)
				(type default)
			)
			(layer "F.Fab")
		)
		(fp_line
			(start 0.12065 -0.3048)
			(end 0.67945 -0.3048)
			(stroke
				(width 0.1)
				(type default)
			)
			(layer "F.Fab")
		)
		(fp_line
			(start 0.67945 -0.3048)
			(end 0.67945 0.3048)
			(stroke
				(width 0.1)
				(type default)
			)
			(layer "F.Fab")
		)
		(fp_line
			(start -0.67945 -0.305054)
			(end -0.12065 -0.305054)
			(stroke
				(width 0.1)
				(type default)
			)
			(layer "F.Fab")
		)
		(fp_line
			(start -0.12065 -0.305054)
			(end -0.12065 -0.2794)
			(stroke
				(width 0.1)
				(type default)
			)
			(layer "F.Fab")
		)
		(pad "1" smd circle
			(at -0.40005 0 270)
			(size 0 0)
			(layers "F.Cu" "F.Mask" "F.Paste")
			(net "RST_RT_CPU1_P1_PERST_R_N")
		)
		(pad "2" smd circle
			(at 0.40005 0 270)
			(size 0 0)
			(layers "F.Cu" "F.Mask" "F.Paste")
			(net "RST_RT_CPU1_P1_PERST_R2_N")
		)
	)
	(footprint ""
		(layer "F.Cu")
		(at 365.701326 -43.235118 -90)
		(property "Reference" "R817"
			(at 0 0 270)
			(layer "F.SilkS")
			(hide yes)
			(effects
				(font
					(size 1.27 1.27)
				)
			)
		)
		(property "Value" ""
			(at 0 0 270)
			(layer "F.Fab")
			(effects
				(font
					(size 1.27 1.27)
				)
			)
		)
		(duplicate_pad_numbers_are_jumpers no)
		(fp_line
			(start -0.7874 0.4064)
			(end -0.7874 -0.4064)
			(stroke
				(width 0.1524)
				(type default)
			)
			(layer "F.SilkS")
		)
		(fp_line
			(start 0.7874 0.4064)
			(end -0.7874 0.4064)
			(stroke
				(width 0.1524)
				(type default)
			)
			(layer "F.SilkS")
		)
		(fp_line
			(start -0.7874 -0.4064)
			(end 0.7874 -0.4064)
			(stroke
				(width 0.1524)
				(type default)
			)
			(layer "F.SilkS")
		)
		(fp_line
			(start 0.7874 -0.4064)
			(end 0.7874 0.4064)
			(stroke
				(width 0.1524)
				(type default)
			)
			(layer "F.SilkS")
		)
		(fp_line
			(start -0.67945 0.3048)
			(end -0.67945 -0.305054)
			(stroke
				(width 0.1)
				(type default)
			)
			(layer "F.Fab")
		)
		(fp_line
			(start -0.12065 0.3048)
			(end -0.67945 0.3048)
			(stroke
				(width 0.1)
				(type default)
			)
			(layer "F.Fab")
		)
		(fp_line
			(start 0.120396 0.3048)
			(end 0.120396 0.2794)
			(stroke
				(width 0.1)
				(type default)
			)
			(layer "F.Fab")
		)
		(fp_line
			(start 0.67945 0.3048)
			(end 0.120396 0.3048)
			(stroke
				(width 0.1)
				(type default)
			)
			(layer "F.Fab")
		)
		(fp_line
			(start -0.12065 0.2794)
			(end -0.12065 0.3048)
			(stroke
				(width 0.1)
				(type default)
			)
			(layer "F.Fab")
		)
		(fp_line
			(start 0.120396 0.2794)
			(end -0.12065 0.2794)
			(stroke
				(width 0.1)
				(type default)
			)
			(layer "F.Fab")
		)
		(fp_line
			(start -0.12065 -0.2794)
			(end 0.12065 -0.2794)
			(stroke
				(width 0.1)
				(type default)
			)
			(layer "F.Fab")
		)
		(fp_line
			(start 0.12065 -0.2794)
			(end 0.12065 -0.3048)
			(stroke
				(width 0.1)
				(type default)
			)
			(layer "F.Fab")
		)
		(fp_line
			(start 0.12065 -0.3048)
			(end 0.67945 -0.3048)
			(stroke
				(width 0.1)
				(type default)
			)
			(layer "F.Fab")
		)
		(fp_line
			(start 0.67945 -0.3048)
			(end 0.67945 0.3048)
			(stroke
				(width 0.1)
				(type default)
			)
			(layer "F.Fab")
		)
		(fp_line
			(start -0.67945 -0.305054)
			(end -0.12065 -0.305054)
			(stroke
				(width 0.1)
				(type default)
			)
			(layer "F.Fab")
		)
		(fp_line
			(start -0.12065 -0.305054)
			(end -0.12065 -0.2794)
			(stroke
				(width 0.1)
				(type default)
			)
			(layer "F.Fab")
		)
		(pad "1" smd circle
			(at -0.40005 0 270)
			(size 0 0)
			(layers "F.Cu" "F.Mask" "F.Paste")
			(net "UART_CPU0_UART0_RX")
		)
		(pad "2" smd circle
			(at 0.40005 0 270)
			(size 0 0)
			(layers "F.Cu" "F.Mask" "F.Paste")
			(net "UART_CPU0_UART0_R_RX")
		)
	)
	(footprint ""
		(layer "F.Cu")
		(at 253.506224 -134.892796 180)
		(property "Reference" "R608"
			(at 0 0 180)
			(layer "F.SilkS")
			(hide yes)
			(effects
				(font
					(size 1.27 1.27)
				)
			)
		)
		(property "Value" ""
			(at 0 0 180)
			(layer "F.Fab")
			(effects
				(font
					(size 1.27 1.27)
				)
			)
		)
		(duplicate_pad_numbers_are_jumpers no)
		(fp_line
			(start 0.7874 0.4064)
			(end -0.7874 0.4064)
			(stroke
				(width 0.1524)
				(type default)
			)
			(layer "F.SilkS")
		)
		(fp_line
			(start 0.7874 -0.4064)
			(end 0.7874 0.4064)
			(stroke
				(width 0.1524)
				(type default)
			)
			(layer "F.SilkS")
		)
		(fp_line
			(start -0.7874 0.4064)
			(end -0.7874 -0.4064)
			(stroke
				(width 0.1524)
				(type default)
			)
			(layer "F.SilkS")
		)
		(fp_line
			(start -0.7874 -0.4064)
			(end 0.7874 -0.4064)
			(stroke
				(width 0.1524)
				(type default)
			)
			(layer "F.SilkS")
		)
		(fp_line
			(start 0.67945 0.3048)
			(end 0.120396 0.3048)
			(stroke
				(width 0.1)
				(type default)
			)
			(layer "F.Fab")
		)
		(fp_line
			(start 0.67945 -0.3048)
			(end 0.67945 0.3048)
			(stroke
				(width 0.1)
				(type default)
			)
			(layer "F.Fab")
		)
		(fp_line
			(start 0.12065 -0.2794)
			(end 0.12065 -0.3048)
			(stroke
				(width 0.1)
				(type default)
			)
			(layer "F.Fab")
		)
		(fp_line
			(start 0.12065 -0.3048)
			(end 0.67945 -0.3048)
			(stroke
				(width 0.1)
				(type default)
			)
			(layer "F.Fab")
		)
		(fp_line
			(start 0.120396 0.3048)
			(end 0.120396 0.2794)
			(stroke
				(width 0.1)
				(type default)
			)
			(layer "F.Fab")
		)
		(fp_line
			(start 0.120396 0.2794)
			(end -0.12065 0.2794)
			(stroke
				(width 0.1)
				(type default)
			)
			(layer "F.Fab")
		)
		(fp_line
			(start -0.12065 0.3048)
			(end -0.67945 0.3048)
			(stroke
				(width 0.1)
				(type default)
			)
			(layer "F.Fab")
		)
		(fp_line
			(start -0.12065 0.2794)
			(end -0.12065 0.3048)
			(stroke
				(width 0.1)
				(type default)
			)
			(layer "F.Fab")
		)
		(fp_line
			(start -0.12065 -0.2794)
			(end 0.12065 -0.2794)
			(stroke
				(width 0.1)
				(type default)
			)
			(layer "F.Fab")
		)
		(fp_line
			(start -0.12065 -0.305054)
			(end -0.12065 -0.2794)
			(stroke
				(width 0.1)
				(type default)
			)
			(layer "F.Fab")
		)
		(fp_line
			(start -0.67945 0.3048)
			(end -0.67945 -0.305054)
			(stroke
				(width 0.1)
				(type default)
			)
			(layer "F.Fab")
		)
		(fp_line
			(start -0.67945 -0.305054)
			(end -0.12065 -0.305054)
			(stroke
				(width 0.1)
				(type default)
			)
			(layer "F.Fab")
		)
		(pad "1" smd circle
			(at -0.40005 0 180)
			(size 0 0)
			(layers "F.Cu" "F.Mask" "F.Paste")
			(net "SPI_CPU0_LVC3_R_TPM_CS_N")
		)
		(pad "2" smd circle
			(at 0.40005 0 180)
			(size 0 0)
			(layers "F.Cu" "F.Mask" "F.Paste")
			(net "SPI_CPU0_LVC3_TPM_CS_N")
		)
	)
)
